# S9S_MB_2U (Grand Teton) — schematic netlist excerpt (pin names and nets, part order shuffled) for the footprints in the layout excerpt that follows; sources: Cadence DE-HDL packaged netlist, KiCad conversion of 03242023_DA0F0TMBIJ0_F0T_Motherboard_J_brd_V01_OCP.brd

R927  Q_RES  10K 1% CHIP  pkg 0402LF  page 221 : A = P3V3_AUX ; B = JTAG_BMC_PLD_TDI
R3269  Q_RES  1K 1% EMPTY  pkg 0402LF  page 166 : A = P3V3_AUX ; B = FM_P2E_FGB

(kicad_pcb
	(version 20260206)
	(generator "pcbnew")
	(generator_version "10.0")
	(general
		(thickness 1.6)
		(legacy_teardrops no)
	)
	(paper "A4")
	(title_block
		(title "03242023_DA0F0TMBIJ0_F0T_Motherboard_J_brd_V01_OCP.brd")
		(comment 1 "Grand Teton / footprints 1833-1834 of 6105")
	)
	(layers
		(0 "F.Cu" signal "TOP")
		(4 "In1.Cu" signal "GND")
		(6 "In2.Cu" signal "IN1")
		(8 "In3.Cu" signal "GND1")
		(10 "In4.Cu" signal "IN2")
		(12 "In5.Cu" signal "GND2")
		(14 "In6.Cu" signal "IN3")
		(16 "In7.Cu" signal "GND3")
		(18 "In8.Cu" signal "VCC")
		(20 "In9.Cu" signal "VCC1")
		(22 "In10.Cu" signal "GND4")
		(24 "In11.Cu" signal "IN4")
		(26 "In12.Cu" signal "GND5")
		(28 "In13.Cu" signal "IN5")
		(30 "In14.Cu" signal "GND6")
		(32 "In15.Cu" signal "IN6")
		(34 "In16.Cu" signal "GND7")
		(2 "B.Cu" signal "BOTTOM")
		(9 "F.Adhes" user "F.Adhesive")
		(11 "B.Adhes" user "B.Adhesive")
		(13 "F.Paste" user "Package Geometry/Pastemask Top")
		(15 "B.Paste" user "Package Geometry/Pastemask Bottom")
		(5 "F.SilkS" user "Ref Des/Silkscreen Top")
		(7 "B.SilkS" user "Ref Des/Silkscreen Bottom")
		(1 "F.Mask" user "Board Geometry/Soldermask Top")
		(3 "B.Mask" user "Board Geometry/Soldermask Bottom")
		(17 "Dwgs.User" user "User.Drawings")
		(19 "Cmts.User" user "User.Comments")
		(21 "Eco1.User" user "User.Eco1")
		(23 "Eco2.User" user "User.Eco2")
		(25 "Edge.Cuts" user "Board Geometry/Outline")
		(27 "Margin" user)
		(31 "F.CrtYd" user "Package Geometry/Place Bound Top")
		(29 "B.CrtYd" user "Package Geometry/Place Bound Bottom")
		(35 "F.Fab" user "Ref Des/Assembly Top")
		(33 "B.Fab" user "Ref Des/Assembly Bottom")
	)
	(footprint ""
		(layer "F.Cu")
		(at 126.770384 -66.856356 90)
		(property "Reference" "R927"
			(at 0 0 90)
			(layer "F.SilkS")
			(hide yes)
			(effects
				(font
					(size 1.27 1.27)
				)
			)
		)
		(property "Value" ""
			(at 0 0 90)
			(layer "F.Fab")
			(effects
				(font
					(size 1.27 1.27)
				)
			)
		)
		(duplicate_pad_numbers_are_jumpers no)
		(fp_line
			(start 0.7874 -0.4064)
			(end 0.7874 0.4064)
			(stroke
				(width 0.1524)
				(type default)
			)
			(layer "F.SilkS")
		)
		(fp_line
			(start -0.7874 -0.4064)
			(end 0.7874 -0.4064)
			(stroke
				(width 0.1524)
				(type default)
			)
			(layer "F.SilkS")
		)
		(fp_line
			(start 0.7874 0.4064)
			(end -0.7874 0.4064)
			(stroke
				(width 0.1524)
				(type default)
			)
			(layer "F.SilkS")
		)
		(fp_line
			(start -0.7874 0.4064)
			(end -0.7874 -0.4064)
			(stroke
				(width 0.1524)
				(type default)
			)
			(layer "F.SilkS")
		)
		(fp_line
			(start -0.12065 -0.305054)
			(end -0.12065 -0.2794)
			(stroke
				(width 0.1)
				(type default)
			)
			(layer "F.Fab")
		)
		(fp_line
			(start -0.67945 -0.305054)
			(end -0.12065 -0.305054)
			(stroke
				(width 0.1)
				(type default)
			)
			(layer "F.Fab")
		)
		(fp_line
			(start 0.67945 -0.3048)
			(end 0.67945 0.3048)
			(stroke
				(width 0.1)
				(type default)
			)
			(layer "F.Fab")
		)
		(fp_line
			(start 0.12065 -0.3048)
			(end 0.67945 -0.3048)
			(stroke
				(width 0.1)
				(type default)
			)
			(layer "F.Fab")
		)
		(fp_line
			(start 0.12065 -0.2794)
			(end 0.12065 -0.3048)
			(stroke
				(width 0.1)
				(type default)
			)
			(layer "F.Fab")
		)
		(fp_line
			(start -0.12065 -0.2794)
			(end 0.12065 -0.2794)
			(stroke
				(width 0.1)
				(type default)
			)
			(layer "F.Fab")
		)
		(fp_line
			(start 0.120396 0.2794)
			(end -0.12065 0.2794)
			(stroke
				(width 0.1)
				(type default)
			)
			(layer "F.Fab")
		)
		(fp_line
			(start -0.12065 0.2794)
			(end -0.12065 0.3048)
			(stroke
				(width 0.1)
				(type default)
			)
			(layer "F.Fab")
		)
		(fp_line
			(start 0.67945 0.3048)
			(end 0.120396 0.3048)
			(stroke
				(width 0.1)
				(type default)
			)
			(layer "F.Fab")
		)
		(fp_line
			(start 0.120396 0.3048)
			(end 0.120396 0.2794)
			(stroke
				(width 0.1)
				(type default)
			)
			(layer "F.Fab")
		)
		(fp_line
			(start -0.12065 0.3048)
			(end -0.67945 0.3048)
			(stroke
				(width 0.1)
				(type default)
			)
			(layer "F.Fab")
		)
		(fp_line
			(start -0.67945 0.3048)
			(end -0.67945 -0.305054)
			(stroke
				(width 0.1)
				(type default)
			)
			(layer "F.Fab")
		)
		(pad "1" smd circle
			(at -0.40005 0 90)
			(size 0 0)
			(layers "F.Cu" "F.Mask" "F.Paste")
			(net "P3V3_AUX")
		)
		(pad "2" smd circle
			(at 0.40005 0 90)
			(size 0 0)
			(layers "F.Cu" "F.Mask" "F.Paste")
			(net "JTAG_BMC_PLD_TDI")
		)
	)
	(footprint ""
		(layer "F.Cu")
		(at 27.628596 -394.358876 180)
		(property "Reference" "R3269"
			(at 0 0 180)
			(layer "F.SilkS")
			(hide yes)
			(effects
				(font
					(size 1.27 1.27)
				)
			)
		)
		(property "Value" ""
			(at 0 0 180)
			(layer "F.Fab")
			(effects
				(font
					(size 1.27 1.27)
				)
			)
		)
		(duplicate_pad_numbers_are_jumpers no)
		(fp_line
			(start 0.7874 0.4064)
			(end -0.7874 0.4064)
			(stroke
				(width 0.1524)
				(type default)
			)
			(layer "F.SilkS")
		)
		(fp_line
			(start 0.7874 -0.4064)
			(end 0.7874 0.4064)
			(stroke
				(width 0.1524)
				(type default)
			)
			(layer "F.SilkS")
		)
		(fp_line
			(start -0.7874 0.4064)
			(end -0.7874 -0.4064)
			(stroke
				(width 0.1524)
				(type default)
			)
			(layer "F.SilkS")
		)
		(fp_line
			(start -0.7874 -0.4064)
			(end 0.7874 -0.4064)
			(stroke
				(width 0.1524)
				(type default)
			)
			(layer "F.SilkS")
		)
		(fp_line
			(start 0.67945 0.3048)
			(end 0.120396 0.3048)
			(stroke
				(width 0.1)
				(type default)
			)
			(layer "F.Fab")
		)
		(fp_line
			(start 0.67945 -0.3048)
			(end 0.67945 0.3048)
			(stroke
				(width 0.1)
				(type default)
			)
			(layer "F.Fab")
		)
		(fp_line
			(start 0.12065 -0.2794)
			(end 0.12065 -0.3048)
			(stroke
				(width 0.1)
				(type default)
			)
			(layer "F.Fab")
		)
		(fp_line
			(start 0.12065 -0.3048)
			(end 0.67945 -0.3048)
			(stroke
				(width 0.1)
				(type default)
			)
			(layer "F.Fab")
		)
		(fp_line
			(start 0.120396 0.3048)
			(end 0.120396 0.2794)
			(stroke
				(width 0.1)
				(type default)
			)
			(layer "F.Fab")
		)
		(fp_line
			(start 0.120396 0.2794)
			(end -0.12065 0.2794)
			(stroke
				(width 0.1)
				(type default)
			)
			(layer "F.Fab")
		)
		(fp_line
			(start -0.12065 0.3048)
			(end -0.67945 0.3048)
			(stroke
				(width 0.1)
				(type default)
			)
			(layer "F.Fab")
		)
		(fp_line
			(start -0.12065 0.2794)
			(end -0.12065 0.3048)
			(stroke
				(width 0.1)
				(type default)
			)
			(layer "F.Fab")
		)
		(fp_line
			(start -0.12065 -0.2794)
			(end 0.12065 -0.2794)
			(stroke
				(width 0.1)
				(type default)
			)
			(layer "F.Fab")
		)
		(fp_line
			(start -0.12065 -0.305054)
			(end -0.12065 -0.2794)
			(stroke
				(width 0.1)
				(type default)
			)
			(layer "F.Fab")
		)
		(fp_line
			(start -0.67945 0.3048)
			(end -0.67945 -0.305054)
			(stroke
				(width 0.1)
				(type default)
			)
			(layer "F.Fab")
		)
		(fp_line
			(start -0.67945 -0.305054)
			(end -0.12065 -0.305054)
			(stroke
				(width 0.1)
				(type default)
			)
			(layer "F.Fab")
		)
		(pad "1" smd circle
			(at -0.40005 0 180)
			(size 0 0)
			(layers "F.Cu" "F.Mask" "F.Paste")
			(net "P3V3_AUX")
		)
		(pad "2" smd circle
			(at 0.40005 0 180)
			(size 0 0)
			(layers "F.Cu" "F.Mask" "F.Paste")
			(net "FM_P2E_FGB")
		)
	)
)
